(kicad_pcb
	(version 20241229)
	(generator "pcbnew")
	(generator_version "9.0")
	(general
		(thickness 1.294)
		(legacy_teardrops no)
	)
	(paper "A3")
	(title_block
		(title "Kintex 410T devboard")
		(date "2024-04-03")
		(rev "1.1.2")
		(comment 9 "footprints 591-596 of 975")
	)
	(layers
		(0 "F.Cu" mixed)
		(4 "In1.Cu" power)
		(6 "In2.Cu" power)
		(8 "In3.Cu" mixed)
		(10 "In4.Cu" power)
		(12 "In5.Cu" mixed)
		(14 "In6.Cu" power)
		(16 "In7.Cu" mixed)
		(18 "In8.Cu" power)
		(2 "B.Cu" mixed)
		(9 "F.Adhes" user "F.Adhesive")
		(11 "B.Adhes" user "B.Adhesive")
		(13 "F.Paste" user)
		(15 "B.Paste" user)
		(5 "F.SilkS" user "F.Silkscreen")
		(7 "B.SilkS" user "B.Silkscreen")
		(1 "F.Mask" user)
		(3 "B.Mask" user)
		(17 "Dwgs.User" user "User.Drawings")
		(19 "Cmts.User" user "User.Comments")
		(21 "Eco1.User" user "User.Eco1")
		(23 "Eco2.User" user "User.Eco2")
		(25 "Edge.Cuts" user)
		(27 "Margin" user)
		(31 "F.CrtYd" user "F.Courtyard")
		(29 "B.CrtYd" user "B.Courtyard")
		(35 "F.Fab" user)
		(33 "B.Fab" user)
	)
	(footprint "antmicro-footprints:R_0402_1005Metric"
		(layer "B.Cu")
		(at 176.1 167.8 180)
		(descr "Resistor SMD 0402")
		(tags "resistor SMD 0402")
		(property "Reference" "R363"
			(at -1.3 0.575 0)
			(layer "B.SilkS")
			(effects
				(font
					(size 0.7 0.7)
					(thickness 0.15)
				)
				(justify left bottom mirror)
			)
		)
		(property "Value" "R_0R_0402"
			(at 0 -1.4 0)
			(layer "B.Fab")
			(effects
				(font
					(size 0.7 0.7)
					(thickness 0.15)
				)
				(justify left bottom mirror)
			)
		)
		(property "Description" "SMD Chip Resistor, Jumper, 0 ohm, 100 mW, 0402 [1005 Metric], Thick Film, General Purpose"
			(at 0 0 180)
			(layer "F.Fab")
			(hide yes)
			(effects
				(font
					(size 1.27 1.27)
					(thickness 0.15)
				)
			)
		)
		(property "Author" "Antmicro"
			(at 352.2 335.6 0)
			(layer "B.Fab")
			(hide yes)
			(effects
				(font
					(size 1 1)
					(thickness 0.15)
				)
				(justify mirror)
			)
		)
		(property "Current" "1A"
			(at 352.2 335.6 0)
			(layer "B.Fab")
			(hide yes)
			(effects
				(font
					(size 1 1)
					(thickness 0.15)
				)
				(justify mirror)
			)
		)
		(property "DNP" "DNP"
			(at 352.2 335.6 0)
			(layer "B.Fab")
			(hide yes)
			(effects
				(font
					(size 1 1)
					(thickness 0.15)
				)
				(justify mirror)
			)
		)
		(property "License" "Apache-2.0"
			(at 352.2 335.6 0)
			(layer "B.Fab")
			(hide yes)
			(effects
				(font
					(size 1 1)
					(thickness 0.15)
				)
				(justify mirror)
			)
		)
		(property "MPN" "ERJ2GE0R00X"
			(at 352.2 335.6 0)
			(layer "B.Fab")
			(hide yes)
			(effects
				(font
					(size 1 1)
					(thickness 0.15)
				)
				(justify mirror)
			)
		)
		(property "Manufacturer" "Panasonic"
			(at 352.2 335.6 0)
			(layer "B.Fab")
			(hide yes)
			(effects
				(font
					(size 1 1)
					(thickness 0.15)
				)
				(justify mirror)
			)
		)
		(property "Tolerance" ""
			(at 352.2 335.6 0)
			(layer "B.Fab")
			(hide yes)
			(effects
				(font
					(size 1 1)
					(thickness 0.15)
				)
				(justify mirror)
			)
		)
		(property "Val" "0R"
			(at 352.2 335.6 0)
			(layer "B.Fab")
			(hide yes)
			(effects
				(font
					(size 1 1)
					(thickness 0.15)
				)
				(justify mirror)
			)
		)
		(property "dnp" ""
			(at 352.2 335.6 0)
			(layer "B.Fab")
			(hide yes)
			(effects
				(font
					(size 1 1)
					(thickness 0.15)
				)
				(justify mirror)
			)
		)
		(property "exclude_from_bom" ""
			(at 352.2 335.6 0)
			(layer "B.Fab")
			(hide yes)
			(effects
				(font
					(size 1 1)
					(thickness 0.15)
				)
				(justify mirror)
			)
		)
		(sheetname "DC-DC Converters")
		(sheetfile "dc-dc.kicad_sch")
		(attr smd exclude_from_bom)
		(fp_rect
			(start -0.925 0.47)
			(end 0.925 -0.47)
			(stroke
				(width 0.05)
				(type default)
			)
			(fill no)
			(layer "B.CrtYd")
		)
		(fp_rect
			(start -0.5 0.25)
			(end 0.5 -0.25)
			(stroke
				(width 0.15)
				(type solid)
			)
			(fill no)
			(layer "B.Fab")
		)
		(pad "1" smd roundrect
			(at -0.48 0 180)
			(size 0.59 0.64)
			(layers "B.Cu" "B.Mask" "B.Paste")
			(roundrect_rratio 0.25)
			(net 1052 "/DC-DC Converters/SW2")
			(pintype "passive")
		)
		(pad "2" smd roundrect
			(at 0.48 0 180)
			(size 0.59 0.64)
			(layers "B.Cu" "B.Mask" "B.Paste")
			(roundrect_rratio 0.25)
			(net 1143 "/DC-DC Converters/SW1")
			(pintype "passive")
		)
	)
	(footprint "antmicro-footprints:C_0402_1005Metric"
		(layer "B.Cu")
		(at 190 138.5)
		(descr "Capacitor SMD 0402")
		(tags "capacitor SMD 0402")
		(property "Reference" "C375"
			(at 0.925 1.275 180)
			(layer "B.SilkS")
			(effects
				(font
					(size 0.7 0.7)
					(thickness 0.15)
				)
				(justify left bottom mirror)
			)
		)
		(property "Value" "C_100n_0402"
			(at 0 -1.169 180)
			(layer "B.Fab")
			(effects
				(font
					(size 0.7 0.7)
					(thickness 0.15)
				)
				(justify left bottom mirror)
			)
		)
		(property "Description" "SMD Multilayer Ceramic Capacitor, 0.1 µF, 50 V, 0402 [1005 Metric], ± 10%, X5R, GRM Series"
			(at 0 0 0)
			(layer "F.Fab")
			(hide yes)
			(effects
				(font
					(size 1.27 1.27)
					(thickness 0.15)
				)
			)
		)
		(property "Author" "Antmicro"
			(at 0 0 0)
			(layer "B.Fab")
			(hide yes)
			(effects
				(font
					(size 1 1)
					(thickness 0.15)
				)
				(justify mirror)
			)
		)
		(property "Dielectric" "X5R"
			(at 0 0 0)
			(layer "B.Fab")
			(hide yes)
			(effects
				(font
					(size 1 1)
					(thickness 0.15)
				)
				(justify mirror)
			)
		)
		(property "License" "Apache-2.0"
			(at 0 0 0)
			(layer "B.Fab")
			(hide yes)
			(effects
				(font
					(size 1 1)
					(thickness 0.15)
				)
				(justify mirror)
			)
		)
		(property "MPN" "GRM155R61H104KE14D"
			(at 0 0 0)
			(layer "B.Fab")
			(hide yes)
			(effects
				(font
					(size 1 1)
					(thickness 0.15)
				)
				(justify mirror)
			)
		)
		(property "Manufacturer" "Murata"
			(at 0 0 0)
			(layer "B.Fab")
			(hide yes)
			(effects
				(font
					(size 1 1)
					(thickness 0.15)
				)
				(justify mirror)
			)
		)
		(property "Val" "100n"
			(at 0 0 0)
			(layer "B.Fab")
			(hide yes)
			(effects
				(font
					(size 1 1)
					(thickness 0.15)
				)
				(justify mirror)
			)
		)
		(property "Voltage" "50V"
			(at 0 0 0)
			(layer "B.Fab")
			(hide yes)
			(effects
				(font
					(size 1 1)
					(thickness 0.15)
				)
				(justify mirror)
			)
		)
		(sheetname "FPGA Bank 33 & 34")
		(sheetfile "fpga-bank-33-34.kicad_sch")
		(attr smd)
		(fp_rect
			(start -0.925 0.47)
			(end 0.925 -0.47)
			(stroke
				(width 0.05)
				(type default)
			)
			(fill no)
			(layer "B.CrtYd")
		)
		(fp_line
			(start -0.494 -0.248)
			(end -0.494 0.25)
			(stroke
				(width 0.15)
				(type solid)
			)
			(layer "B.Fab")
		)
		(fp_line
			(start -0.494 0.25)
			(end 0.504 0.25)
			(stroke
				(width 0.15)
				(type solid)
			)
			(layer "B.Fab")
		)
		(fp_line
			(start 0.504 -0.248)
			(end -0.494 -0.248)
			(stroke
				(width 0.15)
				(type solid)
			)
			(layer "B.Fab")
		)
		(fp_line
			(start 0.504 0.25)
			(end 0.504 -0.248)
			(stroke
				(width 0.15)
				(type solid)
			)
			(layer "B.Fab")
		)
		(pad "1" smd roundrect
			(at -0.48 0)
			(size 0.59 0.64)
			(layers "B.Cu" "B.Mask" "B.Paste")
			(roundrect_rratio 0.25)
			(net 1 "GND")
			(pintype "passive")
		)
		(pad "2" smd roundrect
			(at 0.48 0)
			(size 0.59 0.64)
			(layers "B.Cu" "B.Mask" "B.Paste")
			(roundrect_rratio 0.25)
			(net 11 "+0V675_VREF")
			(pintype "passive")
		)
	)
	(footprint "antmicro-footprints:R_0402_1005Metric"
		(layer "B.Cu")
		(at 265.936 148.3)
		(descr "Resistor SMD 0402")
		(tags "resistor SMD 0402")
		(property "Reference" "R58"
			(at -3.851 0.325 180)
			(layer "B.SilkS")
			(effects
				(font
					(size 0.7 0.7)
					(thickness 0.15)
				)
				(justify left bottom mirror)
			)
		)
		(property "Value" "R_1k_0402"
			(at 0 -1.4 180)
			(layer "B.Fab")
			(effects
				(font
					(size 0.7 0.7)
					(thickness 0.15)
				)
				(justify left bottom mirror)
			)
		)
		(property "Description" "SMD Chip Resistor, 1 kohm, ± 1%, 63 mW, 0402 [1005 Metric], Thick Film, General Purpose"
			(at 0 0 0)
			(layer "F.Fab")
			(hide yes)
			(effects
				(font
					(size 1.27 1.27)
					(thickness 0.15)
				)
			)
		)
		(property "Author" "Antmicro"
			(at 0 0 0)
			(layer "B.Fab")
			(hide yes)
			(effects
				(font
					(size 1 1)
					(thickness 0.15)
				)
				(justify mirror)
			)
		)
		(property "License" "Apache-2.0"
			(at 0 0 0)
			(layer "B.Fab")
			(hide yes)
			(effects
				(font
					(size 1 1)
					(thickness 0.15)
				)
				(justify mirror)
			)
		)
		(property "MPN" "CR0402-FX-1001GLF"
			(at 0 0 0)
			(layer "B.Fab")
			(hide yes)
			(effects
				(font
					(size 1 1)
					(thickness 0.15)
				)
				(justify mirror)
			)
		)
		(property "Manufacturer" "Bourns"
			(at 0 0 0)
			(layer "B.Fab")
			(hide yes)
			(effects
				(font
					(size 1 1)
					(thickness 0.15)
				)
				(justify mirror)
			)
		)
		(property "Tolerance" "1%"
			(at 0 0 0)
			(layer "B.Fab")
			(hide yes)
			(effects
				(font
					(size 1 1)
					(thickness 0.15)
				)
				(justify mirror)
			)
		)
		(property "Val" "1k"
			(at 0 0 0)
			(layer "B.Fab")
			(hide yes)
			(effects
				(font
					(size 1 1)
					(thickness 0.15)
				)
				(justify mirror)
			)
		)
		(sheetname "Power supply")
		(sheetfile "power-supply.kicad_sch")
		(attr smd)
		(fp_rect
			(start -0.925 0.47)
			(end 0.925 -0.47)
			(stroke
				(width 0.05)
				(type default)
			)
			(fill no)
			(layer "B.CrtYd")
		)
		(fp_rect
			(start -0.5 0.25)
			(end 0.5 -0.25)
			(stroke
				(width 0.15)
				(type solid)
			)
			(fill no)
			(layer "B.Fab")
		)
		(pad "1" smd roundrect
			(at -0.48 0)
			(size 0.59 0.64)
			(layers "B.Cu" "B.Mask" "B.Paste")
			(roundrect_rratio 0.25)
			(net 24 "+3V3")
			(pintype "passive")
		)
		(pad "2" smd roundrect
			(at 0.48 0)
			(size 0.59 0.64)
			(layers "B.Cu" "B.Mask" "B.Paste")
			(roundrect_rratio 0.25)
			(net 19 "Net-(D11-A)")
			(pintype "passive")
		)
	)
	(footprint "antmicro-footprints:R_1206_3216Metric"
		(layer "B.Cu")
		(at 255.231 178.63 90)
		(property "Reference" "R47"
			(at 2.255 1.019 0)
			(layer "B.SilkS")
			(effects
				(font
					(size 0.7 0.7)
					(thickness 0.15)
				)
				(justify left bottom mirror)
			)
		)
		(property "Value" "R_1k3_1206"
			(at 0 -2 270)
			(layer "B.Fab")
			(effects
				(font
					(size 0.7 0.7)
					(thickness 0.15)
				)
				(justify left bottom mirror)
			)
		)
		(property "Description" "SMT Chip Resistor, 1.3 kohm, ± 1%, 250 mW, 1206 [3216 Metric], Thick Film, General Purpose"
			(at 0 0 90)
			(layer "F.Fab")
			(hide yes)
			(effects
				(font
					(size 1.27 1.27)
					(thickness 0.15)
				)
			)
		)
		(property "Author" "Antmicro"
			(at 433.861 -76.601 0)
			(layer "B.Fab")
			(hide yes)
			(effects
				(font
					(size 1 1)
					(thickness 0.15)
				)
				(justify mirror)
			)
		)
		(property "License" "Apache-2.0"
			(at 433.861 -76.601 0)
			(layer "B.Fab")
			(hide yes)
			(effects
				(font
					(size 1 1)
					(thickness 0.15)
				)
				(justify mirror)
			)
		)
		(property "MPN" "CR1206-JW-132ELF"
			(at 433.861 -76.601 0)
			(layer "B.Fab")
			(hide yes)
			(effects
				(font
					(size 1 1)
					(thickness 0.15)
				)
				(justify mirror)
			)
		)
		(property "Manufacturer" "Bourns"
			(at 433.861 -76.601 0)
			(layer "B.Fab")
			(hide yes)
			(effects
				(font
					(size 1 1)
					(thickness 0.15)
				)
				(justify mirror)
			)
		)
		(property "Tolerance" "1%"
			(at 433.861 -76.601 0)
			(layer "B.Fab")
			(hide yes)
			(effects
				(font
					(size 1 1)
					(thickness 0.15)
				)
				(justify mirror)
			)
		)
		(property "Val" "1k3"
			(at 433.861 -76.601 0)
			(layer "B.Fab")
			(hide yes)
			(effects
				(font
					(size 1 1)
					(thickness 0.15)
				)
				(justify mirror)
			)
		)
		(sheetname "Power supply")
		(sheetfile "power-supply.kicad_sch")
		(attr smd)
		(fp_line
			(start 0.8 -0.901)
			(end -0.8 -0.901)
			(stroke
				(width 0.15)
				(type solid)
			)
			(layer "B.SilkS")
		)
		(fp_line
			(start 0.8 0.899)
			(end -0.8 0.899)
			(stroke
				(width 0.15)
				(type solid)
			)
			(layer "B.SilkS")
		)
		(fp_rect
			(start -2.325 1.15)
			(end 2.325 -1.15)
			(stroke
				(width 0.05)
				(type default)
			)
			(fill no)
			(layer "B.CrtYd")
		)
		(fp_line
			(start -1.601 -0.8)
			(end 1.6 -0.8)
			(stroke
				(width 0.15)
				(type solid)
			)
			(layer "B.Fab")
		)
		(fp_line
			(start 1.6 0.802)
			(end 1.6 -0.8)
			(stroke
				(width 0.15)
				(type solid)
			)
			(layer "B.Fab")
		)
		(fp_line
			(start -1.601 0.802)
			(end -1.601 -0.8)
			(stroke
				(width 0.15)
				(type solid)
			)
			(layer "B.Fab")
		)
		(fp_line
			(start -1.601 0.802)
			(end 1.6 0.802)
			(stroke
				(width 0.15)
				(type solid)
			)
			(layer "B.Fab")
		)
		(pad "1" smd roundrect
			(at -1.5 -0.001 90)
			(size 1.15 1.8)
			(layers "B.Cu" "B.Mask" "B.Paste")
			(roundrect_rratio 0.25)
			(net 697 "/Power supply/VSS")
			(pintype "passive")
		)
		(pad "2" smd roundrect
			(at 1.5 -0.001 90)
			(size 1.15 1.8)
			(layers "B.Cu" "B.Mask" "B.Paste")
			(roundrect_rratio 0.25)
			(net 881 "/Power supply/AMPS_CTL")
			(pintype "passive")
		)
	)
	(footprint "antmicro-footprints:C_0201"
		(layer "B.Cu")
		(at 184.350001 127.500001)
		(descr "Capacitor SMD 0201")
		(tags "capacitor SMD 0201")
		(property "Reference" "C161"
			(at -3.350001 0.374999 0)
			(layer "B.SilkS")
			(effects
				(font
					(size 0.7 0.7)
					(thickness 0.15)
				)
				(justify right bottom mirror)
			)
		)
		(property "Value" "C_4u7_0201"
			(at 0 -1.4 0)
			(layer "B.Fab")
			(effects
				(font
					(size 0.7 0.7)
					(thickness 0.15)
				)
				(justify right bottom mirror)
			)
		)
		(property "Description" "SMD Multilayer Ceramic Capacitor, 4.7 µF, 6.3 V, 0201 [0603 Metric], ± 20%, X5R, GRM Series"
			(at 0 0 0)
			(layer "F.Fab")
			(hide yes)
			(effects
				(font
					(size 1.27 1.27)
					(thickness 0.15)
				)
			)
		)
		(property "Author" "Antmicro"
			(at 0 0 0)
			(layer "B.Fab")
			(hide yes)
			(effects
				(font
					(size 1 1)
					(thickness 0.15)
				)
				(justify mirror)
			)
		)
		(property "Dielectric" ""
			(at 0 0 0)
			(layer "B.Fab")
			(hide yes)
			(effects
				(font
					(size 1 1)
					(thickness 0.15)
				)
				(justify mirror)
			)
		)
		(property "License" "Apache-2.0"
			(at 0 0 0)
			(layer "B.Fab")
			(hide yes)
			(effects
				(font
					(size 1 1)
					(thickness 0.15)
				)
				(justify mirror)
			)
		)
		(property "MPN" "GRM035R60J475ME15D"
			(at 0 0 0)
			(layer "B.Fab")
			(hide yes)
			(effects
				(font
					(size 1 1)
					(thickness 0.15)
				)
				(justify mirror)
			)
		)
		(property "Manufacturer" "Murata"
			(at 0 0 0)
			(layer "B.Fab")
			(hide yes)
			(effects
				(font
					(size 1 1)
					(thickness 0.15)
				)
				(justify mirror)
			)
		)
		(property "Val" "4u7"
			(at 0 0 0)
			(layer "B.Fab")
			(hide yes)
			(effects
				(font
					(size 1 1)
					(thickness 0.15)
				)
				(justify mirror)
			)
		)
		(property "Voltage" ""
			(at 0 0 0)
			(layer "B.Fab")
			(hide yes)
			(effects
				(font
					(size 1 1)
					(thickness 0.15)
				)
				(justify mirror)
			)
		)
		(sheetname "FPGA supply")
		(sheetfile "fpga-supply.kicad_sch")
		(attr smd)
		(fp_rect
			(start -0.7 0.35)
			(end 0.7 -0.35)
			(stroke
				(width 0.05)
				(type default)
			)
			(fill no)
			(layer "B.CrtYd")
		)
		(fp_rect
			(start 0.3 -0.15)
			(end -0.301 0.149)
			(stroke
				(width 0.15)
				(type solid)
			)
			(fill no)
			(layer "B.Fab")
		)
		(pad "" smd roundrect
			(at -0.349 0.002)
			(size 0.318 0.36)
			(layers "B.Paste")
			(roundrect_rratio 0.25)
		)
		(pad "" smd roundrect
			(at 0.341 0.002)
			(size 0.318 0.36)
			(layers "B.Paste")
			(roundrect_rratio 0.25)
		)
		(pad "1" smd roundrect
			(at -0.321 0.002)
			(size 0.46 0.4)
			(layers "B.Cu" "B.Mask")
			(roundrect_rratio 0.25)
			(net 1 "GND")
			(pintype "passive")
		)
		(pad "2" smd roundrect
			(at 0.32 0.002)
			(size 0.46 0.4)
			(layers "B.Cu" "B.Mask")
			(roundrect_rratio 0.25)
			(net 8 "+1V2_MGTAVTT")
			(pintype "passive")
		)
	)
	(footprint "antmicro-footprints:R_0402_1005Metric"
		(layer "B.Cu")
		(at 158.825001 79.930001 90)
		(descr "Resistor SMD 0402")
		(tags "resistor SMD 0402")
		(property "Reference" "R264"
			(at 1.305001 -0.500001 270)
			(layer "B.SilkS")
			(effects
				(font
					(size 0.7 0.7)
					(thickness 0.15)
				)
				(justify left bottom mirror)
			)
		)
		(property "Value" "R_100k_0402"
			(at 0 -1.4 270)
			(layer "B.Fab")
			(effects
				(font
					(size 0.7 0.7)
					(thickness 0.15)
				)
				(justify left bottom mirror)
			)
		)
		(property "Description" "SMD Chip Resistor, 100 kohm, ± 1%, 62.5 mW, 0402 [1005 Metric], Thick Film, General Purpose"
			(at 0 0 90)
			(layer "F.Fab")
			(hide yes)
			(effects
				(font
					(size 1.27 1.27)
					(thickness 0.15)
				)
			)
		)
		(property "Author" "Antmicro"
			(at 238.755002 -78.895 0)
			(layer "B.Fab")
			(hide yes)
			(effects
				(font
					(size 1 1)
					(thickness 0.15)
				)
				(justify mirror)
			)
		)
		(property "License" "Apache-2.0"
			(at 238.755002 -78.895 0)
			(layer "B.Fab")
			(hide yes)
			(effects
				(font
					(size 1 1)
					(thickness 0.15)
				)
				(justify mirror)
			)
		)
		(property "MPN" "CR0402-FX-1003GLF"
			(at 238.755002 -78.895 0)
			(layer "B.Fab")
			(hide yes)
			(effects
				(font
					(size 1 1)
					(thickness 0.15)
				)
				(justify mirror)
			)
		)
		(property "Manufacturer" "Bourns"
			(at 238.755002 -78.895 0)
			(layer "B.Fab")
			(hide yes)
			(effects
				(font
					(size 1 1)
					(thickness 0.15)
				)
				(justify mirror)
			)
		)
		(property "Tolerance" "1%"
			(at 238.755002 -78.895 0)
			(layer "B.Fab")
			(hide yes)
			(effects
				(font
					(size 1 1)
					(thickness 0.15)
				)
				(justify mirror)
			)
		)
		(property "Val" "100k"
			(at 238.755002 -78.895 0)
			(layer "B.Fab")
			(hide yes)
			(effects
				(font
					(size 1 1)
					(thickness 0.15)
				)
				(justify mirror)
			)
		)
		(sheetname "FMC+ HSPC")
		(sheetfile "fmc-hspc.kicad_sch")
		(attr smd)
		(fp_rect
			(start -0.925 0.47)
			(end 0.925 -0.47)
			(stroke
				(width 0.05)
				(type default)
			)
			(fill no)
			(layer "B.CrtYd")
		)
		(fp_rect
			(start -0.5 0.25)
			(end 0.5 -0.25)
			(stroke
				(width 0.15)
				(type solid)
			)
			(fill no)
			(layer "B.Fab")
		)
		(pad "1" smd roundrect
			(at -0.48 0 90)
			(size 0.59 0.64)
			(layers "B.Cu" "B.Mask" "B.Paste")
			(roundrect_rratio 0.25)
			(net 696 "/FMC+ HSPC/FMC.PRSNT_M2C")
			(pintype "passive")
		)
		(pad "2" smd roundrect
			(at 0.48 0 90)
			(size 0.59 0.64)
			(layers "B.Cu" "B.Mask" "B.Paste")
			(roundrect_rratio 0.25)
			(net 24 "+3V3")
			(pintype "passive")
		)
	)
)
